# T6G (Grand Teton) — schematic netlist excerpt (pin names and nets, part order shuffled) for the footprints in the layout excerpt that follows; sources: Cadence DE-HDL packaged netlist, KiCad conversion of 04192023_DAF0TMB3IC0_F0TG_MB_C_brd_V02_OCP.brd

C558  Q_CAP  0.1UF 10V 10% X7S  pkg C0201  page 279 : A = P0V9_CPU0_RT0_2A ; B = GND
PC6512  Q_CAP  22UF 4V 20% X6S  pkg C0805  page 360 : A = P1V8_CPU0_RT_1D ; B = GND
R567  Q_RES  0 5% CHIP  pkg 0402LF  page 159 : A = I3C_1_SPD_DDRGL_CPU1_SDA ; B = I3C_1_SPD_DDRGL_CPU1_R_SDA

(kicad_pcb
	(version 20260206)
	(generator "pcbnew")
	(generator_version "10.0")
	(general
		(thickness 1.6)
		(legacy_teardrops no)
	)
	(paper "A4")
	(title_block
		(title "04192023_DAF0TMB3IC0_F0TG_MB_C_brd_V02_OCP.brd")
		(comment 1 "Grand Teton / footprints 5869-5871 of 8354")
	)
	(layers
		(0 "F.Cu" signal "TOP")
		(4 "In1.Cu" signal "GND")
		(6 "In2.Cu" signal "IN1")
		(8 "In3.Cu" signal "GND1")
		(10 "In4.Cu" signal "IN2")
		(12 "In5.Cu" signal "GND2")
		(14 "In6.Cu" signal "IN3")
		(16 "In7.Cu" signal "GND3")
		(18 "In8.Cu" signal "VCC")
		(20 "In9.Cu" signal "VCC1")
		(22 "In10.Cu" signal "GND4")
		(24 "In11.Cu" signal "IN4")
		(26 "In12.Cu" signal "GND5")
		(28 "In13.Cu" signal "IN5")
		(30 "In14.Cu" signal "GND6")
		(32 "In15.Cu" signal "IN6")
		(34 "In16.Cu" signal "GND7")
		(2 "B.Cu" signal "BOTTOM")
		(9 "F.Adhes" user "F.Adhesive")
		(11 "B.Adhes" user "B.Adhesive")
		(13 "F.Paste" user "Package Geometry/Pastemask Top")
		(15 "B.Paste" user "Package Geometry/Pastemask Bottom")
		(5 "F.SilkS" user "Ref Des/Silkscreen Top")
		(7 "B.SilkS" user "Ref Des/Silkscreen Bottom")
		(1 "F.Mask" user "Board Geometry/Soldermask Top")
		(3 "B.Mask" user "Board Geometry/Soldermask Bottom")
		(17 "Dwgs.User" user "User.Drawings")
		(19 "Cmts.User" user "User.Comments")
		(21 "Eco1.User" user "User.Eco1")
		(23 "Eco2.User" user "User.Eco2")
		(25 "Edge.Cuts" user "Board Geometry/Outline")
		(27 "Margin" user)
		(31 "F.CrtYd" user "Package Geometry/Place Bound Top")
		(29 "B.CrtYd" user "Package Geometry/Place Bound Bottom")
		(35 "F.Fab" user "Ref Des/Assembly Top")
		(33 "B.Fab" user "Ref Des/Assembly Bottom")
	)
	(footprint ""
		(layer "B.Cu")
		(at 245.873778 -315.95568 -90)
		(property "Reference" "PC6512"
			(at 0 0 90)
			(layer "B.SilkS")
			(hide yes)
			(effects
				(font
					(size 1.27 1.27)
				)
				(justify mirror)
			)
		)
		(property "Value" ""
			(at 0 0 90)
			(layer "B.Fab")
			(effects
				(font
					(size 1.27 1.27)
				)
				(justify mirror)
			)
		)
		(duplicate_pad_numbers_are_jumpers no)
		(fp_line
			(start -1.524 0.762)
			(end 1.524 0.762)
			(stroke
				(width 0.1524)
				(type default)
			)
			(layer "B.SilkS")
		)
		(fp_line
			(start 1.524 0.762)
			(end 1.524 -0.762)
			(stroke
				(width 0.1524)
				(type default)
			)
			(layer "B.SilkS")
		)
		(fp_line
			(start -1.524 -0.762)
			(end -1.524 0.762)
			(stroke
				(width 0.1524)
				(type default)
			)
			(layer "B.SilkS")
		)
		(fp_line
			(start 1.524 -0.762)
			(end -1.524 -0.762)
			(stroke
				(width 0.1524)
				(type default)
			)
			(layer "B.SilkS")
		)
		(fp_line
			(start -1.1049 0.724916)
			(end -1.1049 -0.724916)
			(stroke
				(width 0.1)
				(type default)
			)
			(layer "B.Fab")
		)
		(fp_line
			(start 1.1049 0.724916)
			(end -1.1049 0.724916)
			(stroke
				(width 0.1)
				(type default)
			)
			(layer "B.Fab")
		)
		(fp_line
			(start -1.1049 -0.724916)
			(end 1.1049 -0.724916)
			(stroke
				(width 0.1)
				(type default)
			)
			(layer "B.Fab")
		)
		(fp_line
			(start 1.1049 -0.724916)
			(end 1.1049 0.724916)
			(stroke
				(width 0.1)
				(type default)
			)
			(layer "B.Fab")
		)
		(pad "1" smd rect
			(at 0.889 0 270)
			(size 1.016 1.27)
			(layers "B.Cu" "B.Mask" "B.Paste")
			(net "P1V8_CPU0_RT_1D")
		)
		(pad "2" smd rect
			(at -0.889 0 270)
			(size 1.016 1.27)
			(layers "B.Cu" "B.Mask" "B.Paste")
			(net "GND")
		)
	)
	(footprint ""
		(layer "B.Cu")
		(at 161.276284 -192.907412 -90)
		(property "Reference" "R567"
			(at 0 0 90)
			(layer "B.SilkS")
			(hide yes)
			(effects
				(font
					(size 1.27 1.27)
				)
				(justify mirror)
			)
		)
		(property "Value" ""
			(at 0 0 90)
			(layer "B.Fab")
			(effects
				(font
					(size 1.27 1.27)
				)
				(justify mirror)
			)
		)
		(duplicate_pad_numbers_are_jumpers no)
		(fp_line
			(start -0.7874 0.4064)
			(end 0.7874 0.4064)
			(stroke
				(width 0.1524)
				(type default)
			)
			(layer "B.SilkS")
		)
		(fp_line
			(start 0.7874 0.4064)
			(end 0.7874 -0.4064)
			(stroke
				(width 0.1524)
				(type default)
			)
			(layer "B.SilkS")
		)
		(fp_line
			(start -0.7874 -0.4064)
			(end -0.7874 0.4064)
			(stroke
				(width 0.1524)
				(type default)
			)
			(layer "B.SilkS")
		)
		(fp_line
			(start 0.7874 -0.4064)
			(end -0.7874 -0.4064)
			(stroke
				(width 0.1524)
				(type default)
			)
			(layer "B.SilkS")
		)
		(fp_line
			(start -0.67945 0.3048)
			(end -0.120396 0.3048)
			(stroke
				(width 0.1)
				(type default)
			)
			(layer "B.Fab")
		)
		(fp_line
			(start -0.120396 0.3048)
			(end -0.120396 0.2794)
			(stroke
				(width 0.1)
				(type default)
			)
			(layer "B.Fab")
		)
		(fp_line
			(start 0.12065 0.3048)
			(end 0.67945 0.3048)
			(stroke
				(width 0.1)
				(type default)
			)
			(layer "B.Fab")
		)
		(fp_line
			(start 0.67945 0.3048)
			(end 0.67945 -0.305054)
			(stroke
				(width 0.1)
				(type default)
			)
			(layer "B.Fab")
		)
		(fp_line
			(start -0.120396 0.2794)
			(end 0.12065 0.2794)
			(stroke
				(width 0.1)
				(type default)
			)
			(layer "B.Fab")
		)
		(fp_line
			(start 0.12065 0.2794)
			(end 0.12065 0.3048)
			(stroke
				(width 0.1)
				(type default)
			)
			(layer "B.Fab")
		)
		(fp_line
			(start -0.12065 -0.2794)
			(end -0.12065 -0.3048)
			(stroke
				(width 0.1)
				(type default)
			)
			(layer "B.Fab")
		)
		(fp_line
			(start 0.12065 -0.2794)
			(end -0.12065 -0.2794)
			(stroke
				(width 0.1)
				(type default)
			)
			(layer "B.Fab")
		)
		(fp_line
			(start -0.67945 -0.3048)
			(end -0.67945 0.3048)
			(stroke
				(width 0.1)
				(type default)
			)
			(layer "B.Fab")
		)
		(fp_line
			(start -0.12065 -0.3048)
			(end -0.67945 -0.3048)
			(stroke
				(width 0.1)
				(type default)
			)
			(layer "B.Fab")
		)
		(fp_line
			(start 0.12065 -0.305054)
			(end 0.12065 -0.2794)
			(stroke
				(width 0.1)
				(type default)
			)
			(layer "B.Fab")
		)
		(fp_line
			(start 0.67945 -0.305054)
			(end 0.12065 -0.305054)
			(stroke
				(width 0.1)
				(type default)
			)
			(layer "B.Fab")
		)
		(pad "1" smd rect
			(at 0.40005 0 270)
			(size 0.4572 0.508)
			(layers "B.Cu" "B.Mask" "B.Paste")
			(net "I3C_1_SPD_DDRGL_CPU1_SDA")
		)
		(pad "2" smd rect
			(at -0.40005 0 270)
			(size 0.4572 0.508)
			(layers "B.Cu" "B.Mask" "B.Paste")
			(net "I3C_1_SPD_DDRGL_CPU1_R_SDA")
		)
	)
	(footprint ""
		(layer "B.Cu")
		(at 307.118258 -396.393162 -90)
		(property "Reference" "C558"
			(at 0 0 90)
			(layer "B.SilkS")
			(hide yes)
			(effects
				(font
					(size 1.27 1.27)
				)
				(justify mirror)
			)
		)
		(property "Value" ""
			(at 0 0 90)
			(layer "B.Fab")
			(effects
				(font
					(size 1.27 1.27)
				)
				(justify mirror)
			)
		)
		(duplicate_pad_numbers_are_jumpers no)
		(fp_line
			(start -0.299974 0.150114)
			(end 0.299974 0.150114)
			(stroke
				(width 0.1)
				(type default)
			)
			(layer "B.Fab")
		)
		(fp_line
			(start 0.299974 0.150114)
			(end 0.299974 -0.150114)
			(stroke
				(width 0.1)
				(type default)
			)
			(layer "B.Fab")
		)
		(fp_line
			(start -0.299974 -0.150114)
			(end -0.299974 0.150114)
			(stroke
				(width 0.1)
				(type default)
			)
			(layer "B.Fab")
		)
		(fp_line
			(start 0.299974 -0.150114)
			(end -0.299974 -0.150114)
			(stroke
				(width 0.1)
				(type default)
			)
			(layer "B.Fab")
		)
		(pad "1" smd rect
			(at 0.2667 0 90)
			(size 0.3048 0.381)
			(layers "B.Cu" "B.Mask" "B.Paste")
			(net "P0V9_CPU0_RT0_2A")
		)
		(pad "2" smd rect
			(at -0.2667 0 90)
			(size 0.3048 0.381)
			(layers "B.Cu" "B.Mask" "B.Paste")
			(net "GND")
		)
	)
)
